# T6G (Grand Teton) — schematic netlist excerpt (pin names and nets, part order shuffled) for the footprints in the layout excerpt that follows; sources: Cadence DE-HDL packaged netlist, KiCad conversion of 04192023_DAF0TMB3IC0_F0TG_MB_C_brd_V02_OCP.brd

C2590  Q_CAP  22UF 4V 20% X6S  pkg C0402  page 70 : A = PVDDCR_SOC_P0 ; B = GND
R1282  Q_RES  33 5% CHIP  pkg 0402LF  page 81 : A = FM_NCSI_OCP_SFF_R_OE ; B = FM_PLD_OCP_SFF_PWR_GOOD_R

(kicad_pcb
	(version 20260206)
	(generator "pcbnew")
	(generator_version "10.0")
	(general
		(thickness 1.6)
		(legacy_teardrops no)
	)
	(paper "A4")
	(title_block
		(title "04192023_DAF0TMB3IC0_F0TG_MB_C_brd_V02_OCP.brd")
		(comment 1 "Grand Teton / footprints 5592-5593 of 8354")
	)
	(layers
		(0 "F.Cu" signal "TOP")
		(4 "In1.Cu" signal "GND")
		(6 "In2.Cu" signal "IN1")
		(8 "In3.Cu" signal "GND1")
		(10 "In4.Cu" signal "IN2")
		(12 "In5.Cu" signal "GND2")
		(14 "In6.Cu" signal "IN3")
		(16 "In7.Cu" signal "GND3")
		(18 "In8.Cu" signal "VCC")
		(20 "In9.Cu" signal "VCC1")
		(22 "In10.Cu" signal "GND4")
		(24 "In11.Cu" signal "IN4")
		(26 "In12.Cu" signal "GND5")
		(28 "In13.Cu" signal "IN5")
		(30 "In14.Cu" signal "GND6")
		(32 "In15.Cu" signal "IN6")
		(34 "In16.Cu" signal "GND7")
		(2 "B.Cu" signal "BOTTOM")
		(9 "F.Adhes" user "F.Adhesive")
		(11 "B.Adhes" user "B.Adhesive")
		(13 "F.Paste" user "Package Geometry/Pastemask Top")
		(15 "B.Paste" user "Package Geometry/Pastemask Bottom")
		(5 "F.SilkS" user "Ref Des/Silkscreen Top")
		(7 "B.SilkS" user "Ref Des/Silkscreen Bottom")
		(1 "F.Mask" user "Board Geometry/Soldermask Top")
		(3 "B.Mask" user "Board Geometry/Soldermask Bottom")
		(17 "Dwgs.User" user "User.Drawings")
		(19 "Cmts.User" user "User.Comments")
		(21 "Eco1.User" user "User.Eco1")
		(23 "Eco2.User" user "User.Eco2")
		(25 "Edge.Cuts" user "Board Geometry/Outline")
		(27 "Margin" user)
		(31 "F.CrtYd" user "Package Geometry/Place Bound Top")
		(29 "B.CrtYd" user "Package Geometry/Place Bound Bottom")
		(35 "F.Fab" user "Ref Des/Assembly Top")
		(33 "B.Fab" user "Ref Des/Assembly Bottom")
	)
	(footprint ""
		(layer "B.Cu")
		(at 370.801646 -261.935976)
		(property "Reference" "C2590"
			(at 0 0 0)
			(layer "B.SilkS")
			(hide yes)
			(effects
				(font
					(size 1.27 1.27)
				)
				(justify mirror)
			)
		)
		(property "Value" ""
			(at 0 0 0)
			(layer "B.Fab")
			(effects
				(font
					(size 1.27 1.27)
				)
				(justify mirror)
			)
		)
		(duplicate_pad_numbers_are_jumpers no)
		(fp_line
			(start -0.7874 -0.4064)
			(end -0.7874 0.4064)
			(stroke
				(width 0.1524)
				(type default)
			)
			(layer "B.SilkS")
		)
		(fp_line
			(start -0.7874 0.4064)
			(end 0.7874 0.4064)
			(stroke
				(width 0.1524)
				(type default)
			)
			(layer "B.SilkS")
		)
		(fp_line
			(start 0.7874 -0.4064)
			(end -0.7874 -0.4064)
			(stroke
				(width 0.1524)
				(type default)
			)
			(layer "B.SilkS")
		)
		(fp_line
			(start 0.7874 0.4064)
			(end 0.7874 -0.4064)
			(stroke
				(width 0.1524)
				(type default)
			)
			(layer "B.SilkS")
		)
		(fp_line
			(start -0.67945 -0.3048)
			(end -0.67945 0.3048)
			(stroke
				(width 0.1)
				(type default)
			)
			(layer "B.Fab")
		)
		(fp_line
			(start -0.67945 0.3048)
			(end -0.120396 0.3048)
			(stroke
				(width 0.1)
				(type default)
			)
			(layer "B.Fab")
		)
		(fp_line
			(start -0.12065 -0.3048)
			(end -0.67945 -0.3048)
			(stroke
				(width 0.1)
				(type default)
			)
			(layer "B.Fab")
		)
		(fp_line
			(start -0.12065 -0.2794)
			(end -0.12065 -0.3048)
			(stroke
				(width 0.1)
				(type default)
			)
			(layer "B.Fab")
		)
		(fp_line
			(start -0.120396 0.2794)
			(end 0.12065 0.2794)
			(stroke
				(width 0.1)
				(type default)
			)
			(layer "B.Fab")
		)
		(fp_line
			(start -0.120396 0.3048)
			(end -0.120396 0.2794)
			(stroke
				(width 0.1)
				(type default)
			)
			(layer "B.Fab")
		)
		(fp_line
			(start 0.12065 -0.305054)
			(end 0.12065 -0.2794)
			(stroke
				(width 0.1)
				(type default)
			)
			(layer "B.Fab")
		)
		(fp_line
			(start 0.12065 -0.2794)
			(end -0.12065 -0.2794)
			(stroke
				(width 0.1)
				(type default)
			)
			(layer "B.Fab")
		)
		(fp_line
			(start 0.12065 0.2794)
			(end 0.12065 0.3048)
			(stroke
				(width 0.1)
				(type default)
			)
			(layer "B.Fab")
		)
		(fp_line
			(start 0.12065 0.3048)
			(end 0.67945 0.3048)
			(stroke
				(width 0.1)
				(type default)
			)
			(layer "B.Fab")
		)
		(fp_line
			(start 0.67945 -0.305054)
			(end 0.12065 -0.305054)
			(stroke
				(width 0.1)
				(type default)
			)
			(layer "B.Fab")
		)
		(fp_line
			(start 0.67945 0.3048)
			(end 0.67945 -0.305054)
			(stroke
				(width 0.1)
				(type default)
			)
			(layer "B.Fab")
		)
		(pad "1" smd circle
			(at 0.40005 0 180)
			(size 0 0)
			(layers "B.Cu" "B.Mask" "B.Paste")
			(net "PVDDCR_SOC_P0")
		)
		(pad "2" smd circle
			(at -0.40005 0 180)
			(size 0 0)
			(layers "B.Cu" "B.Mask" "B.Paste")
			(net "GND")
		)
	)
	(footprint ""
		(layer "B.Cu")
		(at 197.002908 -113.427256)
		(property "Reference" "R1282"
			(at 0 0 0)
			(layer "B.SilkS")
			(hide yes)
			(effects
				(font
					(size 1.27 1.27)
				)
				(justify mirror)
			)
		)
		(property "Value" ""
			(at 0 0 0)
			(layer "B.Fab")
			(effects
				(font
					(size 1.27 1.27)
				)
				(justify mirror)
			)
		)
		(duplicate_pad_numbers_are_jumpers no)
		(fp_line
			(start -0.7874 -0.4064)
			(end -0.7874 0.4064)
			(stroke
				(width 0.1524)
				(type default)
			)
			(layer "B.SilkS")
		)
		(fp_line
			(start -0.7874 0.4064)
			(end 0.7874 0.4064)
			(stroke
				(width 0.1524)
				(type default)
			)
			(layer "B.SilkS")
		)
		(fp_line
			(start 0.7874 -0.4064)
			(end -0.7874 -0.4064)
			(stroke
				(width 0.1524)
				(type default)
			)
			(layer "B.SilkS")
		)
		(fp_line
			(start 0.7874 0.4064)
			(end 0.7874 -0.4064)
			(stroke
				(width 0.1524)
				(type default)
			)
			(layer "B.SilkS")
		)
		(fp_line
			(start -0.67945 -0.3048)
			(end -0.67945 0.3048)
			(stroke
				(width 0.1)
				(type default)
			)
			(layer "B.Fab")
		)
		(fp_line
			(start -0.67945 0.3048)
			(end -0.120396 0.3048)
			(stroke
				(width 0.1)
				(type default)
			)
			(layer "B.Fab")
		)
		(fp_line
			(start -0.12065 -0.3048)
			(end -0.67945 -0.3048)
			(stroke
				(width 0.1)
				(type default)
			)
			(layer "B.Fab")
		)
		(fp_line
			(start -0.12065 -0.2794)
			(end -0.12065 -0.3048)
			(stroke
				(width 0.1)
				(type default)
			)
			(layer "B.Fab")
		)
		(fp_line
			(start -0.120396 0.2794)
			(end 0.12065 0.2794)
			(stroke
				(width 0.1)
				(type default)
			)
			(layer "B.Fab")
		)
		(fp_line
			(start -0.120396 0.3048)
			(end -0.120396 0.2794)
			(stroke
				(width 0.1)
				(type default)
			)
			(layer "B.Fab")
		)
		(fp_line
			(start 0.12065 -0.305054)
			(end 0.12065 -0.2794)
			(stroke
				(width 0.1)
				(type default)
			)
			(layer "B.Fab")
		)
		(fp_line
			(start 0.12065 -0.2794)
			(end -0.12065 -0.2794)
			(stroke
				(width 0.1)
				(type default)
			)
			(layer "B.Fab")
		)
		(fp_line
			(start 0.12065 0.2794)
			(end 0.12065 0.3048)
			(stroke
				(width 0.1)
				(type default)
			)
			(layer "B.Fab")
		)
		(fp_line
			(start 0.12065 0.3048)
			(end 0.67945 0.3048)
			(stroke
				(width 0.1)
				(type default)
			)
			(layer "B.Fab")
		)
		(fp_line
			(start 0.67945 -0.305054)
			(end 0.12065 -0.305054)
			(stroke
				(width 0.1)
				(type default)
			)
			(layer "B.Fab")
		)
		(fp_line
			(start 0.67945 0.3048)
			(end 0.67945 -0.305054)
			(stroke
				(width 0.1)
				(type default)
			)
			(layer "B.Fab")
		)
		(pad "1" smd circle
			(at 0.40005 0 180)
			(size 0 0)
			(layers "B.Cu" "B.Mask" "B.Paste")
			(net "FM_NCSI_OCP_SFF_R_OE")
		)
		(pad "2" smd circle
			(at -0.40005 0 180)
			(size 0 0)
			(layers "B.Cu" "B.Mask" "B.Paste")
			(net "FM_PLD_OCP_SFF_PWR_GOOD_R")
		)
	)
)
